(kicad_pcb
	(version 20260206)
	(generator "pcbnew")
	(generator_version "10.0")
	(general
		(thickness 1.6)
		(legacy_teardrops no)
	)
	(paper "A4")
	(title_block
		(title "Wiwynn_Tioga_Pass_MB.brd")
		(comment 1 "Tioga Pass / footprint 2254 of 4770 (U5D1), pads 2296-2406 of 3647")
	)
	(layers
		(0 "F.Cu" signal "TOP")
		(4 "In1.Cu" signal "L2GND")
		(6 "In2.Cu" signal "L3")
		(8 "In3.Cu" signal "L4GND")
		(10 "In4.Cu" signal "L5")
		(12 "In5.Cu" signal "L6GND")
		(14 "In6.Cu" signal "L7VCC")
		(16 "In7.Cu" signal "L8VCC")
		(18 "In8.Cu" signal "L9GND")
		(20 "In9.Cu" signal "L10")
		(22 "In10.Cu" signal "L11GND")
		(24 "In11.Cu" signal "L12")
		(26 "In12.Cu" signal "L13GND")
		(2 "B.Cu" signal "BOTTOM")
		(9 "F.Adhes" user "F.Adhesive")
		(11 "B.Adhes" user "B.Adhesive")
		(13 "F.Paste" user "Package Geometry/Pastemask Top")
		(15 "B.Paste" user "Package Geometry/Pastemask Bottom")
		(5 "F.SilkS" user "Ref Des/Silkscreen Top")
		(7 "B.SilkS" user "Ref Des/Silkscreen Bottom")
		(1 "F.Mask" user "Board Geometry/Soldermask Top")
		(3 "B.Mask" user "Board Geometry/Soldermask Bottom")
		(17 "Dwgs.User" user "User.Drawings")
		(19 "Cmts.User" user "User.Comments")
		(21 "Eco1.User" user "User.Eco1")
		(23 "Eco2.User" user "User.Eco2")
		(25 "Edge.Cuts" user "Board Geometry/Outline")
		(27 "Margin" user)
		(31 "F.CrtYd" user "Package Geometry/Place Bound Top")
		(29 "B.CrtYd" user "Package Geometry/Place Bound Bottom")
		(35 "F.Fab" user "Ref Des/Assembly Top")
		(33 "B.Fab" user "Ref Des/Assembly Bottom")
	)
	(footprint ""
		(layer "F.Cu")
		(at 270.000222 -76.550012 180)
		(property "Reference" "U5D1"
			(at 19.124422 31.601918 0)
			(unlocked yes)
			(layer "F.SilkS")
			(effects
				(font
					(size 0.7874 0.5842)
					(thickness 0.1524)
				)
			)
		)
		(property "Value" ""
			(at 0 0 180)
			(layer "F.Fab")
			(effects
				(font
					(size 1.27 1.27)
				)
			)
		)
		(duplicate_pad_numbers_are_jumpers no)
		(pad "DJ42" smd circle
			(at -2.052066 18.483072)
			(size 0.4318 0.4318)
			(layers "F.Cu" "F.Mask" "F.Paste")
			(net "GND")
		)
		(pad "DJ44" smd circle
			(at 1.193546 16.683228)
			(size 0.508 0.508)
			(layers "F.Cu" "F.Mask" "F.Paste")
			(net "SVID_DIO1_CPU0")
		)
		(pad "DJ46" smd circle
			(at 2.910586 16.683228)
			(size 0.4318 0.4318)
			(layers "F.Cu" "F.Mask" "F.Paste")
			(net "M_F_CS_N<2>")
		)
		(pad "DJ48" smd circle
			(at 4.627626 16.683228)
			(size 0.4318 0.4318)
			(layers "F.Cu" "F.Mask" "F.Paste")
			(net "M_F_CS_N<5>")
		)
		(pad "DJ50" smd circle
			(at 6.344412 16.683228)
			(size 0.4318 0.4318)
			(layers "F.Cu" "F.Mask" "F.Paste")
			(net "M_F_MA<14>")
		)
		(pad "DJ52" smd circle
			(at 8.061452 16.683228)
			(size 0.4318 0.4318)
			(layers "F.Cu" "F.Mask" "F.Paste")
			(net "M_F_BA<0>")
		)
		(pad "DJ54" smd circle
			(at 9.778492 16.683228)
			(size 0.4318 0.4318)
			(layers "F.Cu" "F.Mask" "F.Paste")
			(net "M_F_CLK_DP<0>")
		)
		(pad "DJ56" smd circle
			(at 11.495532 16.683228)
			(size 0.4318 0.4318)
			(layers "F.Cu" "F.Mask" "F.Paste")
			(net "M_F_CLK_DP<2>")
		)
		(pad "DJ58" smd circle
			(at 13.212572 16.683228)
			(size 0.4318 0.4318)
			(layers "F.Cu" "F.Mask" "F.Paste")
			(net "M_F_MA<4>")
		)
		(pad "DJ60" smd circle
			(at 14.929612 16.683228)
			(size 0.4318 0.4318)
			(layers "F.Cu" "F.Mask" "F.Paste")
			(net "M_E_MA<8>")
		)
		(pad "DJ62" smd circle
			(at 16.646398 16.683228)
			(size 0.4318 0.4318)
			(layers "F.Cu" "F.Mask" "F.Paste")
			(net "M_E_BG<0>")
		)
		(pad "DJ64" smd circle
			(at 18.363438 16.683228)
			(size 0.4318 0.4318)
			(layers "F.Cu" "F.Mask" "F.Paste")
			(net "PVDDQ_DEF")
		)
		(pad "DJ66" smd circle
			(at 20.080478 16.683228)
			(size 0.4318 0.4318)
			(layers "F.Cu" "F.Mask" "F.Paste")
			(net "TP_CPU0_RSVD_40")
		)
		(pad "DJ68" smd circle
			(at 21.797518 16.683228)
			(size 0.4318 0.4318)
			(layers "F.Cu" "F.Mask" "F.Paste")
			(net "GND")
		)
		(pad "DJ70" smd circle
			(at 23.514558 16.683228)
			(size 0.4318 0.4318)
			(layers "F.Cu" "F.Mask" "F.Paste")
			(net "M_F_DQS_DN<11>")
		)
		(pad "DJ72" smd circle
			(at 25.231598 16.683228)
			(size 0.4318 0.4318)
			(layers "F.Cu" "F.Mask" "F.Paste")
			(net "M_F_DQ<17>")
		)
		(pad "DJ74" smd circle
			(at 26.948384 16.683228)
			(size 0.4318 0.4318)
			(layers "F.Cu" "F.Mask" "F.Paste")
			(net "GND")
		)
		(pad "DJ76" smd circle
			(at 28.665424 16.683228)
			(size 0.4318 0.4318)
			(layers "F.Cu" "F.Mask" "F.Paste")
			(net "M_F_DQ<11>")
		)
		(pad "DJ78" smd circle
			(at 30.382464 16.683228)
			(size 0.4318 0.4318)
			(layers "F.Cu" "F.Mask" "F.Paste")
			(net "GND")
		)
		(pad "DJ80" smd circle
			(at 32.099504 16.683228)
			(size 0.4318 0.4318)
			(layers "F.Cu" "F.Mask" "F.Paste")
			(net "M_D_DQ<21>")
		)
		(pad "DJ82" smd circle
			(at 33.816544 16.683228)
			(size 0.4318 0.4318)
			(layers "F.Cu" "F.Mask" "F.Paste")
			(net "GND")
		)
		(pad "DJ84" smd circle
			(at 35.533584 16.683228)
			(size 0.4318 0.4318)
			(layers "F.Cu" "F.Mask" "F.Paste")
			(net "GND")
		)
		(pad "DK3" smd circle
			(at -35.533584 18.978372)
			(size 0.4318 0.4318)
			(layers "F.Cu" "F.Mask" "F.Paste")
			(net "P3E_CPU0_PE1_SS_TXN<5>")
		)
		(pad "DK5" smd circle
			(at -33.816544 18.978372)
			(size 0.4318 0.4318)
			(layers "F.Cu" "F.Mask" "F.Paste")
			(net "P3E_CPU0_PE3_OCP_TXP<10>")
		)
		(pad "DK7" smd circle
			(at -32.099504 18.978372)
			(size 0.4318 0.4318)
			(layers "F.Cu" "F.Mask" "F.Paste")
			(net "GND")
		)
		(pad "DK9" smd circle
			(at -30.382464 18.978372)
			(size 0.4318 0.4318)
			(layers "F.Cu" "F.Mask" "F.Paste")
			(net "P3E_CPU0_PE1_SS_RXN<6>")
		)
		(pad "DK11" smd circle
			(at -28.665424 18.978372)
			(size 0.4318 0.4318)
			(layers "F.Cu" "F.Mask" "F.Paste")
			(net "P3E_CPU0_PE1_PCH_RXP<8>")
		)
		(pad "DK13" smd circle
			(at -26.948384 18.978372)
			(size 0.4318 0.4318)
			(layers "F.Cu" "F.Mask" "F.Paste")
			(net "P3E_CPU0_PE3_OCP_RXP<8>")
		)
		(pad "DK15" smd circle
			(at -25.231598 18.978372)
			(size 0.4318 0.4318)
			(layers "F.Cu" "F.Mask" "F.Paste")
			(net "TP_CPU0_RSVD_39")
		)
		(pad "DK17" smd circle
			(at -23.514558 18.978372)
			(size 0.4318 0.4318)
			(layers "F.Cu" "F.Mask" "F.Paste")
			(net "TP_CPU0_UPI2_RSVD_CJ14")
		)
		(pad "DK19" smd circle
			(at -21.797518 18.978372)
			(size 0.4318 0.4318)
			(layers "F.Cu" "F.Mask" "F.Paste")
			(net "TP_CPU0_UPI2_RSVD_CD11")
		)
		(pad "DK21" smd circle
			(at -20.080478 18.978372)
			(size 0.4318 0.4318)
			(layers "F.Cu" "F.Mask" "F.Paste")
			(net "PVCCIO_CPU0")
		)
		(pad "DK23" smd circle
			(at -18.363438 18.978372)
			(size 0.4318 0.4318)
			(layers "F.Cu" "F.Mask" "F.Paste")
			(net "GND")
		)
		(pad "DK25" smd circle
			(at -16.646398 18.978372)
			(size 0.4318 0.4318)
			(layers "F.Cu" "F.Mask" "F.Paste")
			(net "M_E_DQ<63>")
		)
		(pad "DK27" smd circle
			(at -14.929612 18.978372)
			(size 0.4318 0.4318)
			(layers "F.Cu" "F.Mask" "F.Paste")
			(net "M_E_DQ<57>")
		)
		(pad "DK29" smd circle
			(at -13.212572 18.978372)
			(size 0.4318 0.4318)
			(layers "F.Cu" "F.Mask" "F.Paste")
			(net "GND")
		)
		(pad "DK31" smd circle
			(at -11.495532 18.978372)
			(size 0.4318 0.4318)
			(layers "F.Cu" "F.Mask" "F.Paste")
			(net "M_F_DQ<47>")
		)
		(pad "DK33" smd circle
			(at -9.778492 18.978372)
			(size 0.4318 0.4318)
			(layers "F.Cu" "F.Mask" "F.Paste")
			(net "M_F_DQ<41>")
		)
		(pad "DK35" smd circle
			(at -8.061452 18.978372)
			(size 0.4318 0.4318)
			(layers "F.Cu" "F.Mask" "F.Paste")
			(net "GND")
		)
		(pad "DK37" smd circle
			(at -6.344412 18.978372)
			(size 0.4318 0.4318)
			(layers "F.Cu" "F.Mask" "F.Paste")
			(net "TP_CPU0_RSVD_38")
		)
		(pad "DK39" smd circle
			(at -4.627626 18.978372)
			(size 0.4318 0.4318)
			(layers "F.Cu" "F.Mask" "F.Paste")
			(net "GND")
		)
		(pad "DK41" smd circle
			(at -2.910586 18.978372)
			(size 0.4318 0.4318)
			(layers "F.Cu" "F.Mask" "F.Paste")
			(net "GND")
		)
		(pad "DK45" smd circle
			(at 2.052066 17.178528)
			(size 0.4318 0.4318)
			(layers "F.Cu" "F.Mask" "F.Paste")
			(net "M_F_CS_N<7>")
		)
		(pad "DK47" smd circle
			(at 3.769106 17.178528)
			(size 0.4318 0.4318)
			(layers "F.Cu" "F.Mask" "F.Paste")
			(net "M_E_CS_N<3>")
		)
		(pad "DK49" smd circle
			(at 5.485892 17.178528)
			(size 0.4318 0.4318)
			(layers "F.Cu" "F.Mask" "F.Paste")
			(net "M_F_ODT<2>")
		)
		(pad "DK51" smd circle
			(at 7.202932 17.178528)
			(size 0.4318 0.4318)
			(layers "F.Cu" "F.Mask" "F.Paste")
			(net "M_F_CS_N<0>")
		)
		(pad "DK53" smd circle
			(at 8.919972 17.178528)
			(size 0.4318 0.4318)
			(layers "F.Cu" "F.Mask" "F.Paste")
			(net "M_F_PAR")
		)
		(pad "DK55" smd circle
			(at 10.637012 17.178528)
			(size 0.4318 0.4318)
			(layers "F.Cu" "F.Mask" "F.Paste")
			(net "M_F_CLK_DN<0>")
		)
		(pad "DK57" smd circle
			(at 12.354052 17.178528)
			(size 0.4318 0.4318)
			(layers "F.Cu" "F.Mask" "F.Paste")
			(net "M_F_CLK_DN<2>")
		)
		(pad "DK59" smd circle
			(at 14.071092 17.178528)
			(size 0.4318 0.4318)
			(layers "F.Cu" "F.Mask" "F.Paste")
			(net "M_F_MA<6>")
		)
		(pad "DK61" smd circle
			(at 15.787878 17.178528)
			(size 0.4318 0.4318)
			(layers "F.Cu" "F.Mask" "F.Paste")
			(net "M_E_MA<7>")
		)
		(pad "DK63" smd circle
			(at 17.504918 17.178528)
			(size 0.4318 0.4318)
			(layers "F.Cu" "F.Mask" "F.Paste")
			(net "M_F_CKE<2>")
		)
		(pad "DK65" smd circle
			(at 19.221958 17.178528)
			(size 0.4318 0.4318)
			(layers "F.Cu" "F.Mask" "F.Paste")
			(net "TP_CPU0_RSVD_37")
		)
		(pad "DK67" smd circle
			(at 20.938998 17.178528)
			(size 0.4318 0.4318)
			(layers "F.Cu" "F.Mask" "F.Paste")
			(net "TP_CPU0_RSVD_36")
		)
		(pad "DK69" smd circle
			(at 22.656038 17.178528)
			(size 0.4318 0.4318)
			(layers "F.Cu" "F.Mask" "F.Paste")
			(net "M_F_DQ<22>")
		)
		(pad "DK71" smd circle
			(at 24.373078 17.178528)
			(size 0.4318 0.4318)
			(layers "F.Cu" "F.Mask" "F.Paste")
			(net "M_F_DQS_DP<2>")
		)
		(pad "DK73" smd circle
			(at 26.090118 17.178528)
			(size 0.4318 0.4318)
			(layers "F.Cu" "F.Mask" "F.Paste")
			(net "GND")
		)
		(pad "DK75" smd circle
			(at 27.806904 17.178528)
			(size 0.4318 0.4318)
			(layers "F.Cu" "F.Mask" "F.Paste")
			(net "GND")
		)
		(pad "DK77" smd circle
			(at 29.523944 17.178528)
			(size 0.4318 0.4318)
			(layers "F.Cu" "F.Mask" "F.Paste")
			(net "GND")
		)
		(pad "DK79" smd circle
			(at 31.240984 17.178528)
			(size 0.4318 0.4318)
			(layers "F.Cu" "F.Mask" "F.Paste")
			(net "M_D_DQ<20>")
		)
		(pad "DK81" smd circle
			(at 32.958024 17.178528)
			(size 0.4318 0.4318)
			(layers "F.Cu" "F.Mask" "F.Paste")
			(net "M_D_DQ<17>")
		)
		(pad "DK83" smd circle
			(at 34.675064 17.178528)
			(size 0.4318 0.4318)
			(layers "F.Cu" "F.Mask" "F.Paste")
			(net "GND")
		)
		(pad "DK85" smd custom
			(at 36.392104 17.178528 270)
			(size 0.10795 0.10795)
			(layers "F.Cu" "F.Mask" "F.Paste")
			(net "GND")
			(options
				(clearance outline)
				(anchor circle)
			)
			(primitives
				(gr_poly
					(pts
						(arc
							(start 0.2159 -0.0381)
							(mid 0 -0.254)
							(end -0.2159 -0.0381)
						)
						(arc
							(start -0.2159 0.0381)
							(mid 0 0.254)
							(end 0.2159 0.0381)
						)
					)
					(width 0)
					(fill yes)
				)
			)
		)
		(pad "DL2" smd custom
			(at -36.392104 19.473926 90)
			(size 0.10795 0.10795)
			(layers "F.Cu" "F.Mask" "F.Paste")
			(net "P3E_CPU0_PE1_SS_TXP<6>")
			(options
				(clearance outline)
				(anchor circle)
			)
			(primitives
				(gr_poly
					(pts
						(arc
							(start 0.2159 -0.0381)
							(mid 0 -0.254)
							(end -0.2159 -0.0381)
						)
						(arc
							(start -0.2159 0.0381)
							(mid 0 0.254)
							(end 0.2159 0.0381)
						)
					)
					(width 0)
					(fill yes)
				)
			)
		)
		(pad "DL4" smd circle
			(at -34.675064 19.473926)
			(size 0.4318 0.4318)
			(layers "F.Cu" "F.Mask" "F.Paste")
			(net "GND")
		)
		(pad "DL6" smd circle
			(at -32.958024 19.473926)
			(size 0.4318 0.4318)
			(layers "F.Cu" "F.Mask" "F.Paste")
			(net "P3E_CPU0_PE3_OCP_TXN<10>")
		)
		(pad "DL8" smd circle
			(at -31.240984 19.473926)
			(size 0.4318 0.4318)
			(layers "F.Cu" "F.Mask" "F.Paste")
			(net "GND")
		)
		(pad "DL10" smd circle
			(at -29.523944 19.473926)
			(size 0.4318 0.4318)
			(layers "F.Cu" "F.Mask" "F.Paste")
			(net "P3E_CPU0_PE1_SS_RXP<7>")
		)
		(pad "DL12" smd circle
			(at -27.806904 19.473926)
			(size 0.4318 0.4318)
			(layers "F.Cu" "F.Mask" "F.Paste")
			(net "P3E_CPU0_PE3_OCP_RXN<8>")
		)
		(pad "DL14" smd circle
			(at -26.090118 19.473926)
			(size 0.4318 0.4318)
			(layers "F.Cu" "F.Mask" "F.Paste")
			(net "P3E_CPU0_PE3_OCP_RXN<7>")
		)
		(pad "DL16" smd circle
			(at -24.373078 19.473926)
			(size 0.4318 0.4318)
			(layers "F.Cu" "F.Mask" "F.Paste")
			(net "GND")
		)
		(pad "DL18" smd circle
			(at -22.656038 19.473926)
			(size 0.4318 0.4318)
			(layers "F.Cu" "F.Mask" "F.Paste")
			(net "GND")
		)
		(pad "DL20" smd circle
			(at -20.938998 19.473926)
			(size 0.4318 0.4318)
			(layers "F.Cu" "F.Mask" "F.Paste")
			(net "TP_CPU0_UPI2_RSVD_CE12")
		)
		(pad "DL22" smd circle
			(at -19.221958 19.473926)
			(size 0.4318 0.4318)
			(layers "F.Cu" "F.Mask" "F.Paste")
			(net "GND")
		)
		(pad "DL24" smd circle
			(at -17.504918 19.473926)
			(size 0.4318 0.4318)
			(layers "F.Cu" "F.Mask" "F.Paste")
			(net "GND")
		)
		(pad "DL26" smd circle
			(at -15.787878 19.473926)
			(size 0.4318 0.4318)
			(layers "F.Cu" "F.Mask" "F.Paste")
			(net "M_E_DQS_DN<7>")
		)
		(pad "DL28" smd circle
			(at -14.071092 19.473926)
			(size 0.4318 0.4318)
			(layers "F.Cu" "F.Mask" "F.Paste")
			(net "GND")
		)
		(pad "DL30" smd circle
			(at -12.354052 19.473926)
			(size 0.4318 0.4318)
			(layers "F.Cu" "F.Mask" "F.Paste")
			(net "GND")
		)
		(pad "DL32" smd circle
			(at -10.637012 19.473926)
			(size 0.4318 0.4318)
			(layers "F.Cu" "F.Mask" "F.Paste")
			(net "M_F_DQS_DN<5>")
		)
		(pad "DL34" smd circle
			(at -8.919972 19.473926)
			(size 0.4318 0.4318)
			(layers "F.Cu" "F.Mask" "F.Paste")
			(net "GND")
		)
		(pad "DL36" smd circle
			(at -7.202932 19.473926)
			(size 0.4318 0.4318)
			(layers "F.Cu" "F.Mask" "F.Paste")
			(net "GND")
		)
		(pad "DL38" smd circle
			(at -5.485892 19.473926)
			(size 0.4318 0.4318)
			(layers "F.Cu" "F.Mask" "F.Paste")
			(net "TP_CPU0_RSVD_35")
		)
		(pad "DL40" smd circle
			(at -3.769106 19.473926)
			(size 0.4318 0.4318)
			(layers "F.Cu" "F.Mask" "F.Paste")
			(net "GND")
		)
		(pad "DL42" smd circle
			(at -2.052066 19.473926)
			(size 0.4318 0.4318)
			(layers "F.Cu" "F.Mask" "F.Paste")
			(net "M_E_DQ<36>")
		)
		(pad "DL44" smd circle
			(at 1.193546 17.673574)
			(size 0.508 0.508)
			(layers "F.Cu" "F.Mask" "F.Paste")
			(net "SVID_ALERT1_CPU0_N")
		)
		(pad "DL46" smd circle
			(at 2.910586 17.673574)
			(size 0.4318 0.4318)
			(layers "F.Cu" "F.Mask" "F.Paste")
			(net "PVDDQ_DEF")
		)
		(pad "DL48" smd circle
			(at 4.627626 17.673574)
			(size 0.4318 0.4318)
			(layers "F.Cu" "F.Mask" "F.Paste")
			(net "PVDDQ_DEF")
		)
		(pad "DL50" smd circle
			(at 6.344412 17.673574)
			(size 0.4318 0.4318)
			(layers "F.Cu" "F.Mask" "F.Paste")
			(net "PVDDQ_DEF")
		)
		(pad "DL52" smd circle
			(at 8.061452 17.673574)
			(size 0.4318 0.4318)
			(layers "F.Cu" "F.Mask" "F.Paste")
			(net "PVDDQ_DEF")
		)
		(pad "DL54" smd circle
			(at 9.778492 17.673574)
			(size 0.4318 0.4318)
			(layers "F.Cu" "F.Mask" "F.Paste")
			(net "PVDDQ_DEF")
		)
		(pad "DL56" smd circle
			(at 11.495532 17.673574)
			(size 0.4318 0.4318)
			(layers "F.Cu" "F.Mask" "F.Paste")
			(net "PVDDQ_DEF")
		)
		(pad "DL58" smd circle
			(at 13.212572 17.673574)
			(size 0.4318 0.4318)
			(layers "F.Cu" "F.Mask" "F.Paste")
			(net "PVDDQ_DEF")
		)
		(pad "DL60" smd circle
			(at 14.929612 17.673574)
			(size 0.4318 0.4318)
			(layers "F.Cu" "F.Mask" "F.Paste")
			(net "PVDDQ_DEF")
		)
		(pad "DL62" smd circle
			(at 16.646398 17.673574)
			(size 0.4318 0.4318)
			(layers "F.Cu" "F.Mask" "F.Paste")
			(net "PVDDQ_DEF")
		)
		(pad "DL64" smd circle
			(at 18.363438 17.673574)
			(size 0.4318 0.4318)
			(layers "F.Cu" "F.Mask" "F.Paste")
			(net "M_E_CKE<2>")
		)
		(pad "DL66" smd circle
			(at 20.080478 17.673574)
			(size 0.4318 0.4318)
			(layers "F.Cu" "F.Mask" "F.Paste")
			(net "TP_CPU0_RSVD_34")
		)
		(pad "DL68" smd circle
			(at 21.797518 17.673574)
			(size 0.4318 0.4318)
			(layers "F.Cu" "F.Mask" "F.Paste")
			(net "GND")
		)
		(pad "DL70" smd circle
			(at 23.514558 17.673574)
			(size 0.4318 0.4318)
			(layers "F.Cu" "F.Mask" "F.Paste")
			(net "GND")
		)
		(pad "DL72" smd circle
			(at 25.231598 17.673574)
			(size 0.4318 0.4318)
			(layers "F.Cu" "F.Mask" "F.Paste")
			(net "M_F_DQS_DN<2>")
		)
		(pad "DL74" smd circle
			(at 26.948384 17.673574)
			(size 0.4318 0.4318)
			(layers "F.Cu" "F.Mask" "F.Paste")
			(net "GND")
		)
		(pad "DL76" smd circle
			(at 28.665424 17.673574)
			(size 0.4318 0.4318)
			(layers "F.Cu" "F.Mask" "F.Paste")
			(net "GND")
		)
		(pad "DL78" smd circle
			(at 30.382464 17.673574)
			(size 0.4318 0.4318)
			(layers "F.Cu" "F.Mask" "F.Paste")
			(net "GND")
		)
		(pad "DL80" smd circle
			(at 32.099504 17.673574)
			(size 0.4318 0.4318)
			(layers "F.Cu" "F.Mask" "F.Paste")
			(net "GND")
		)
		(pad "DL82" smd circle
			(at 33.816544 17.673574)
			(size 0.4318 0.4318)
			(layers "F.Cu" "F.Mask" "F.Paste")
			(net "M_D_DQS_DN<2>")
		)
		(pad "DL84" smd circle
			(at 35.533584 17.673574)
			(size 0.4318 0.4318)
			(layers "F.Cu" "F.Mask" "F.Paste")
			(net "M_D_DQS_DP<10>")
		)
		(pad "DM3" smd circle
			(at -35.533584 19.968972)
			(size 0.4318 0.4318)
			(layers "F.Cu" "F.Mask" "F.Paste")
			(net "P3E_CPU0_PE1_SS_TXN<6>")
		)
		(pad "DM5" smd circle
			(at -33.816544 19.968972)
			(size 0.4318 0.4318)
			(layers "F.Cu" "F.Mask" "F.Paste")
			(net "P3E_CPU0_PE3_OCP_TXP<9>")
		)
		(pad "DM7" smd circle
			(at -32.099504 19.968972)
			(size 0.4318 0.4318)
			(layers "F.Cu" "F.Mask" "F.Paste")
			(net "P3E_CPU0_PE3_OCP_TXN<8>")
		)
		(pad "DM9" smd circle
			(at -30.382464 19.968972)
			(size 0.4318 0.4318)
			(layers "F.Cu" "F.Mask" "F.Paste")
			(net "P3E_CPU0_PE1_SS_RXN<7>")
		)
		(pad "DM11" smd circle
			(at -28.665424 19.968972)
			(size 0.4318 0.4318)
			(layers "F.Cu" "F.Mask" "F.Paste")
			(net "P3E_CPU0_PE1_PCH_RXN<8>")
		)
		(pad "DM13" smd circle
			(at -26.948384 19.968972)
			(size 0.4318 0.4318)
			(layers "F.Cu" "F.Mask" "F.Paste")
			(net "P3E_CPU0_PE3_OCP_RXP<6>")
		)
	)
)
